# T6G (Grand Teton) — schematic netlist excerpt (pin names and nets, part order shuffled) for the footprints in the layout excerpt that follows; sources: Cadence DE-HDL packaged netlist, KiCad conversion of 04192023_DAF0TMB3IC0_F0TG_MB_C_brd_V02_OCP.brd

R2585  Q_RES  31.6K 1% CHIP  pkg 0402LF  page 268 : A = HSC_EN ; B = GND
R56  Q_RES  0 5% CHIP  pkg 0402LF  page 80 : A = SMB_1_PLD_3V3AUX_SDA_R1 ; B = SMB_1_PLD_3V3AUX_SDA_R2

(kicad_pcb
	(version 20260206)
	(generator "pcbnew")
	(generator_version "10.0")
	(general
		(thickness 1.6)
		(legacy_teardrops no)
	)
	(paper "A4")
	(title_block
		(title "04192023_DAF0TMB3IC0_F0TG_MB_C_brd_V02_OCP.brd")
		(comment 1 "Grand Teton / footprints 1909-1910 of 8354")
	)
	(layers
		(0 "F.Cu" signal "TOP")
		(4 "In1.Cu" signal "GND")
		(6 "In2.Cu" signal "IN1")
		(8 "In3.Cu" signal "GND1")
		(10 "In4.Cu" signal "IN2")
		(12 "In5.Cu" signal "GND2")
		(14 "In6.Cu" signal "IN3")
		(16 "In7.Cu" signal "GND3")
		(18 "In8.Cu" signal "VCC")
		(20 "In9.Cu" signal "VCC1")
		(22 "In10.Cu" signal "GND4")
		(24 "In11.Cu" signal "IN4")
		(26 "In12.Cu" signal "GND5")
		(28 "In13.Cu" signal "IN5")
		(30 "In14.Cu" signal "GND6")
		(32 "In15.Cu" signal "IN6")
		(34 "In16.Cu" signal "GND7")
		(2 "B.Cu" signal "BOTTOM")
		(9 "F.Adhes" user "F.Adhesive")
		(11 "B.Adhes" user "B.Adhesive")
		(13 "F.Paste" user "Package Geometry/Pastemask Top")
		(15 "B.Paste" user "Package Geometry/Pastemask Bottom")
		(5 "F.SilkS" user "Ref Des/Silkscreen Top")
		(7 "B.SilkS" user "Ref Des/Silkscreen Bottom")
		(1 "F.Mask" user "Board Geometry/Soldermask Top")
		(3 "B.Mask" user "Board Geometry/Soldermask Bottom")
		(17 "Dwgs.User" user "User.Drawings")
		(19 "Cmts.User" user "User.Comments")
		(21 "Eco1.User" user "User.Eco1")
		(23 "Eco2.User" user "User.Eco2")
		(25 "Edge.Cuts" user "Board Geometry/Outline")
		(27 "Margin" user)
		(31 "F.CrtYd" user "Package Geometry/Place Bound Top")
		(29 "B.CrtYd" user "Package Geometry/Place Bound Bottom")
		(35 "F.Fab" user "Ref Des/Assembly Top")
		(33 "B.Fab" user "Ref Des/Assembly Bottom")
	)
	(footprint ""
		(layer "F.Cu")
		(at 271.295876 -418.97173 90)
		(property "Reference" "R2585"
			(at 0 0 90)
			(layer "F.SilkS")
			(hide yes)
			(effects
				(font
					(size 1.27 1.27)
				)
			)
		)
		(property "Value" ""
			(at 0 0 90)
			(layer "F.Fab")
			(effects
				(font
					(size 1.27 1.27)
				)
			)
		)
		(duplicate_pad_numbers_are_jumpers no)
		(fp_line
			(start 0.7874 -0.4064)
			(end 0.7874 0.4064)
			(stroke
				(width 0.1524)
				(type default)
			)
			(layer "F.SilkS")
		)
		(fp_line
			(start -0.7874 -0.4064)
			(end 0.7874 -0.4064)
			(stroke
				(width 0.1524)
				(type default)
			)
			(layer "F.SilkS")
		)
		(fp_line
			(start 0.7874 0.4064)
			(end -0.7874 0.4064)
			(stroke
				(width 0.1524)
				(type default)
			)
			(layer "F.SilkS")
		)
		(fp_line
			(start -0.7874 0.4064)
			(end -0.7874 -0.4064)
			(stroke
				(width 0.1524)
				(type default)
			)
			(layer "F.SilkS")
		)
		(fp_line
			(start -0.12065 -0.305054)
			(end -0.12065 -0.2794)
			(stroke
				(width 0.1)
				(type default)
			)
			(layer "F.Fab")
		)
		(fp_line
			(start -0.67945 -0.305054)
			(end -0.12065 -0.305054)
			(stroke
				(width 0.1)
				(type default)
			)
			(layer "F.Fab")
		)
		(fp_line
			(start 0.67945 -0.3048)
			(end 0.67945 0.3048)
			(stroke
				(width 0.1)
				(type default)
			)
			(layer "F.Fab")
		)
		(fp_line
			(start 0.12065 -0.3048)
			(end 0.67945 -0.3048)
			(stroke
				(width 0.1)
				(type default)
			)
			(layer "F.Fab")
		)
		(fp_line
			(start 0.12065 -0.2794)
			(end 0.12065 -0.3048)
			(stroke
				(width 0.1)
				(type default)
			)
			(layer "F.Fab")
		)
		(fp_line
			(start -0.12065 -0.2794)
			(end 0.12065 -0.2794)
			(stroke
				(width 0.1)
				(type default)
			)
			(layer "F.Fab")
		)
		(fp_line
			(start 0.120396 0.2794)
			(end -0.12065 0.2794)
			(stroke
				(width 0.1)
				(type default)
			)
			(layer "F.Fab")
		)
		(fp_line
			(start -0.12065 0.2794)
			(end -0.12065 0.3048)
			(stroke
				(width 0.1)
				(type default)
			)
			(layer "F.Fab")
		)
		(fp_line
			(start 0.67945 0.3048)
			(end 0.120396 0.3048)
			(stroke
				(width 0.1)
				(type default)
			)
			(layer "F.Fab")
		)
		(fp_line
			(start 0.120396 0.3048)
			(end 0.120396 0.2794)
			(stroke
				(width 0.1)
				(type default)
			)
			(layer "F.Fab")
		)
		(fp_line
			(start -0.12065 0.3048)
			(end -0.67945 0.3048)
			(stroke
				(width 0.1)
				(type default)
			)
			(layer "F.Fab")
		)
		(fp_line
			(start -0.67945 0.3048)
			(end -0.67945 -0.305054)
			(stroke
				(width 0.1)
				(type default)
			)
			(layer "F.Fab")
		)
		(pad "1" smd circle
			(at -0.40005 0 90)
			(size 0 0)
			(layers "F.Cu" "F.Mask" "F.Paste")
			(net "HSC_EN")
		)
		(pad "2" smd circle
			(at 0.40005 0 90)
			(size 0 0)
			(layers "F.Cu" "F.Mask" "F.Paste")
			(net "GND")
		)
	)
	(footprint ""
		(layer "F.Cu")
		(at 171.196 -115.280948)
		(property "Reference" "R56"
			(at 0 0 0)
			(layer "F.SilkS")
			(hide yes)
			(effects
				(font
					(size 1.27 1.27)
				)
			)
		)
		(property "Value" ""
			(at 0 0 0)
			(layer "F.Fab")
			(effects
				(font
					(size 1.27 1.27)
				)
			)
		)
		(duplicate_pad_numbers_are_jumpers no)
		(fp_line
			(start -0.7874 -0.4064)
			(end 0.7874 -0.4064)
			(stroke
				(width 0.1524)
				(type default)
			)
			(layer "F.SilkS")
		)
		(fp_line
			(start -0.7874 0.4064)
			(end -0.7874 -0.4064)
			(stroke
				(width 0.1524)
				(type default)
			)
			(layer "F.SilkS")
		)
		(fp_line
			(start 0.7874 -0.4064)
			(end 0.7874 0.4064)
			(stroke
				(width 0.1524)
				(type default)
			)
			(layer "F.SilkS")
		)
		(fp_line
			(start 0.7874 0.4064)
			(end -0.7874 0.4064)
			(stroke
				(width 0.1524)
				(type default)
			)
			(layer "F.SilkS")
		)
		(fp_line
			(start -0.67945 -0.305054)
			(end -0.12065 -0.305054)
			(stroke
				(width 0.1)
				(type default)
			)
			(layer "F.Fab")
		)
		(fp_line
			(start -0.67945 0.3048)
			(end -0.67945 -0.305054)
			(stroke
				(width 0.1)
				(type default)
			)
			(layer "F.Fab")
		)
		(fp_line
			(start -0.12065 -0.305054)
			(end -0.12065 -0.2794)
			(stroke
				(width 0.1)
				(type default)
			)
			(layer "F.Fab")
		)
		(fp_line
			(start -0.12065 -0.2794)
			(end 0.12065 -0.2794)
			(stroke
				(width 0.1)
				(type default)
			)
			(layer "F.Fab")
		)
		(fp_line
			(start -0.12065 0.2794)
			(end -0.12065 0.3048)
			(stroke
				(width 0.1)
				(type default)
			)
			(layer "F.Fab")
		)
		(fp_line
			(start -0.12065 0.3048)
			(end -0.67945 0.3048)
			(stroke
				(width 0.1)
				(type default)
			)
			(layer "F.Fab")
		)
		(fp_line
			(start 0.120396 0.2794)
			(end -0.12065 0.2794)
			(stroke
				(width 0.1)
				(type default)
			)
			(layer "F.Fab")
		)
		(fp_line
			(start 0.120396 0.3048)
			(end 0.120396 0.2794)
			(stroke
				(width 0.1)
				(type default)
			)
			(layer "F.Fab")
		)
		(fp_line
			(start 0.12065 -0.3048)
			(end 0.67945 -0.3048)
			(stroke
				(width 0.1)
				(type default)
			)
			(layer "F.Fab")
		)
		(fp_line
			(start 0.12065 -0.2794)
			(end 0.12065 -0.3048)
			(stroke
				(width 0.1)
				(type default)
			)
			(layer "F.Fab")
		)
		(fp_line
			(start 0.67945 -0.3048)
			(end 0.67945 0.3048)
			(stroke
				(width 0.1)
				(type default)
			)
			(layer "F.Fab")
		)
		(fp_line
			(start 0.67945 0.3048)
			(end 0.120396 0.3048)
			(stroke
				(width 0.1)
				(type default)
			)
			(layer "F.Fab")
		)
		(pad "1" smd circle
			(at -0.40005 0)
			(size 0 0)
			(layers "F.Cu" "F.Mask" "F.Paste")
			(net "SMB_1_PLD_3V3AUX_SDA_R1")
		)
		(pad "2" smd circle
			(at 0.40005 0)
			(size 0 0)
			(layers "F.Cu" "F.Mask" "F.Paste")
			(net "SMB_1_PLD_3V3AUX_SDA_R2")
		)
	)
)
